# S9S_MB_2U (Grand Teton) — schematic netlist excerpt (pin names and nets, part order shuffled) for the footprints in the layout excerpt that follows; sources: Cadence DE-HDL packaged netlist, KiCad conversion of 03242023_DA0F0TMBIJ0_F0T_Motherboard_J_brd_V01_OCP.brd

H88  HOLE  EMPTY  pkg TH  page 311 : \1\ = GND
R623  Q_RES  1K 1% EMPTY  pkg 0402LF  page 199 : A = P3V3_AUX ; B = FM_PCH_XTALSEL
PR566  Q_RES  100 1% CHIP  pkg 0402LF  page 292 : A = VSENSE_PVCCINFAON_CPU1_DN ; B = GND

(kicad_pcb
	(version 20260206)
	(generator "pcbnew")
	(generator_version "10.0")
	(general
		(thickness 1.6)
		(legacy_teardrops no)
	)
	(paper "A4")
	(title_block
		(title "03242023_DA0F0TMBIJ0_F0T_Motherboard_J_brd_V01_OCP.brd")
		(comment 1 "Grand Teton / footprints 453-455 of 6105")
	)
	(layers
		(0 "F.Cu" signal "TOP")
		(4 "In1.Cu" signal "GND")
		(6 "In2.Cu" signal "IN1")
		(8 "In3.Cu" signal "GND1")
		(10 "In4.Cu" signal "IN2")
		(12 "In5.Cu" signal "GND2")
		(14 "In6.Cu" signal "IN3")
		(16 "In7.Cu" signal "GND3")
		(18 "In8.Cu" signal "VCC")
		(20 "In9.Cu" signal "VCC1")
		(22 "In10.Cu" signal "GND4")
		(24 "In11.Cu" signal "IN4")
		(26 "In12.Cu" signal "GND5")
		(28 "In13.Cu" signal "IN5")
		(30 "In14.Cu" signal "GND6")
		(32 "In15.Cu" signal "IN6")
		(34 "In16.Cu" signal "GND7")
		(2 "B.Cu" signal "BOTTOM")
		(9 "F.Adhes" user "F.Adhesive")
		(11 "B.Adhes" user "B.Adhesive")
		(13 "F.Paste" user "Package Geometry/Pastemask Top")
		(15 "B.Paste" user "Package Geometry/Pastemask Bottom")
		(5 "F.SilkS" user "Ref Des/Silkscreen Top")
		(7 "B.SilkS" user "Ref Des/Silkscreen Bottom")
		(1 "F.Mask" user "Board Geometry/Soldermask Top")
		(3 "B.Mask" user "Board Geometry/Soldermask Bottom")
		(17 "Dwgs.User" user "User.Drawings")
		(19 "Cmts.User" user "User.Comments")
		(21 "Eco1.User" user "User.Eco1")
		(23 "Eco2.User" user "User.Eco2")
		(25 "Edge.Cuts" user "Board Geometry/Outline")
		(27 "Margin" user)
		(31 "F.CrtYd" user "Package Geometry/Place Bound Top")
		(29 "B.CrtYd" user "Package Geometry/Place Bound Bottom")
		(35 "F.Fab" user "Ref Des/Assembly Top")
		(33 "B.Fab" user "Ref Des/Assembly Bottom")
	)
	(footprint ""
		(layer "F.Cu")
		(at 317.396622 -54.803548)
		(property "Reference" "R623"
			(at 0 0 0)
			(layer "F.SilkS")
			(hide yes)
			(effects
				(font
					(size 1.27 1.27)
				)
			)
		)
		(property "Value" ""
			(at 0 0 0)
			(layer "F.Fab")
			(effects
				(font
					(size 1.27 1.27)
				)
			)
		)
		(duplicate_pad_numbers_are_jumpers no)
		(fp_line
			(start -0.7874 -0.4064)
			(end 0.7874 -0.4064)
			(stroke
				(width 0.1524)
				(type default)
			)
			(layer "F.SilkS")
		)
		(fp_line
			(start -0.7874 0.4064)
			(end -0.7874 -0.4064)
			(stroke
				(width 0.1524)
				(type default)
			)
			(layer "F.SilkS")
		)
		(fp_line
			(start 0.7874 -0.4064)
			(end 0.7874 0.4064)
			(stroke
				(width 0.1524)
				(type default)
			)
			(layer "F.SilkS")
		)
		(fp_line
			(start 0.7874 0.4064)
			(end -0.7874 0.4064)
			(stroke
				(width 0.1524)
				(type default)
			)
			(layer "F.SilkS")
		)
		(fp_line
			(start -0.67945 -0.305054)
			(end -0.12065 -0.305054)
			(stroke
				(width 0.1)
				(type default)
			)
			(layer "F.Fab")
		)
		(fp_line
			(start -0.67945 0.3048)
			(end -0.67945 -0.305054)
			(stroke
				(width 0.1)
				(type default)
			)
			(layer "F.Fab")
		)
		(fp_line
			(start -0.12065 -0.305054)
			(end -0.12065 -0.2794)
			(stroke
				(width 0.1)
				(type default)
			)
			(layer "F.Fab")
		)
		(fp_line
			(start -0.12065 -0.2794)
			(end 0.12065 -0.2794)
			(stroke
				(width 0.1)
				(type default)
			)
			(layer "F.Fab")
		)
		(fp_line
			(start -0.12065 0.2794)
			(end -0.12065 0.3048)
			(stroke
				(width 0.1)
				(type default)
			)
			(layer "F.Fab")
		)
		(fp_line
			(start -0.12065 0.3048)
			(end -0.67945 0.3048)
			(stroke
				(width 0.1)
				(type default)
			)
			(layer "F.Fab")
		)
		(fp_line
			(start 0.120396 0.2794)
			(end -0.12065 0.2794)
			(stroke
				(width 0.1)
				(type default)
			)
			(layer "F.Fab")
		)
		(fp_line
			(start 0.120396 0.3048)
			(end 0.120396 0.2794)
			(stroke
				(width 0.1)
				(type default)
			)
			(layer "F.Fab")
		)
		(fp_line
			(start 0.12065 -0.3048)
			(end 0.67945 -0.3048)
			(stroke
				(width 0.1)
				(type default)
			)
			(layer "F.Fab")
		)
		(fp_line
			(start 0.12065 -0.2794)
			(end 0.12065 -0.3048)
			(stroke
				(width 0.1)
				(type default)
			)
			(layer "F.Fab")
		)
		(fp_line
			(start 0.67945 -0.3048)
			(end 0.67945 0.3048)
			(stroke
				(width 0.1)
				(type default)
			)
			(layer "F.Fab")
		)
		(fp_line
			(start 0.67945 0.3048)
			(end 0.120396 0.3048)
			(stroke
				(width 0.1)
				(type default)
			)
			(layer "F.Fab")
		)
		(pad "1" smd circle
			(at -0.40005 0)
			(size 0 0)
			(layers "F.Cu" "F.Mask" "F.Paste")
			(net "P3V3_AUX")
		)
		(pad "2" smd circle
			(at 0.40005 0)
			(size 0 0)
			(layers "F.Cu" "F.Mask" "F.Paste")
			(net "FM_PCH_XTALSEL")
		)
	)
	(footprint ""
		(layer "F.Cu")
		(at 73.28408 -144.665192 180)
		(property "Reference" "PR566"
			(at 0 0 180)
			(layer "F.SilkS")
			(hide yes)
			(effects
				(font
					(size 1.27 1.27)
				)
			)
		)
		(property "Value" ""
			(at 0 0 180)
			(layer "F.Fab")
			(effects
				(font
					(size 1.27 1.27)
				)
			)
		)
		(duplicate_pad_numbers_are_jumpers no)
		(fp_line
			(start 0.7874 0.4064)
			(end -0.7874 0.4064)
			(stroke
				(width 0.1524)
				(type default)
			)
			(layer "F.SilkS")
		)
		(fp_line
			(start 0.7874 -0.4064)
			(end 0.7874 0.4064)
			(stroke
				(width 0.1524)
				(type default)
			)
			(layer "F.SilkS")
		)
		(fp_line
			(start -0.7874 0.4064)
			(end -0.7874 -0.4064)
			(stroke
				(width 0.1524)
				(type default)
			)
			(layer "F.SilkS")
		)
		(fp_line
			(start -0.7874 -0.4064)
			(end 0.7874 -0.4064)
			(stroke
				(width 0.1524)
				(type default)
			)
			(layer "F.SilkS")
		)
		(fp_line
			(start 0.67945 0.3048)
			(end 0.120396 0.3048)
			(stroke
				(width 0.1)
				(type default)
			)
			(layer "F.Fab")
		)
		(fp_line
			(start 0.67945 -0.3048)
			(end 0.67945 0.3048)
			(stroke
				(width 0.1)
				(type default)
			)
			(layer "F.Fab")
		)
		(fp_line
			(start 0.12065 -0.2794)
			(end 0.12065 -0.3048)
			(stroke
				(width 0.1)
				(type default)
			)
			(layer "F.Fab")
		)
		(fp_line
			(start 0.12065 -0.3048)
			(end 0.67945 -0.3048)
			(stroke
				(width 0.1)
				(type default)
			)
			(layer "F.Fab")
		)
		(fp_line
			(start 0.120396 0.3048)
			(end 0.120396 0.2794)
			(stroke
				(width 0.1)
				(type default)
			)
			(layer "F.Fab")
		)
		(fp_line
			(start 0.120396 0.2794)
			(end -0.12065 0.2794)
			(stroke
				(width 0.1)
				(type default)
			)
			(layer "F.Fab")
		)
		(fp_line
			(start -0.12065 0.3048)
			(end -0.67945 0.3048)
			(stroke
				(width 0.1)
				(type default)
			)
			(layer "F.Fab")
		)
		(fp_line
			(start -0.12065 0.2794)
			(end -0.12065 0.3048)
			(stroke
				(width 0.1)
				(type default)
			)
			(layer "F.Fab")
		)
		(fp_line
			(start -0.12065 -0.2794)
			(end 0.12065 -0.2794)
			(stroke
				(width 0.1)
				(type default)
			)
			(layer "F.Fab")
		)
		(fp_line
			(start -0.12065 -0.305054)
			(end -0.12065 -0.2794)
			(stroke
				(width 0.1)
				(type default)
			)
			(layer "F.Fab")
		)
		(fp_line
			(start -0.67945 0.3048)
			(end -0.67945 -0.305054)
			(stroke
				(width 0.1)
				(type default)
			)
			(layer "F.Fab")
		)
		(fp_line
			(start -0.67945 -0.305054)
			(end -0.12065 -0.305054)
			(stroke
				(width 0.1)
				(type default)
			)
			(layer "F.Fab")
		)
		(pad "1" smd circle
			(at -0.40005 0 180)
			(size 0 0)
			(layers "F.Cu" "F.Mask" "F.Paste")
			(net "VSENSE_PVCCINFAON_CPU1_DN")
		)
		(pad "2" smd circle
			(at 0.40005 0 180)
			(size 0 0)
			(layers "F.Cu" "F.Mask" "F.Paste")
			(net "GND")
		)
	)
	(footprint ""
		(layer "F.Cu")
		(at 322.90004 -160.50006)
		(property "Reference" "H88"
			(at -6.47192 -4.13131 0)
			(unlocked yes)
			(layer "F.SilkS")
			(effects
				(font
					(size 0.7874 0.5842)
					(thickness 0.1524)
				)
				(justify left)
			)
		)
		(property "Value" ""
			(at 0 0 0)
			(layer "F.Fab")
			(effects
				(font
					(size 1.27 1.27)
				)
			)
		)
		(duplicate_pad_numbers_are_jumpers no)
		(pad "1" thru_hole circle
			(at 0 0)
			(size 10.0076 10.0076)
			(drill 5.6134)
			(layers "*.Cu" "*.Mask")
			(remove_unused_layers no)
			(net "GND")
			(clearance -1.9431)
		)
	)
)
